# BASEBOARD_FAB2 (Tioga Pass) — schematic netlist excerpt (pin names and nets, part order shuffled) for the footprints in the layout excerpt that follows; sources: Cadence DE-HDL packaged netlist, KiCad conversion of Wiwynn_Tioga_Pass_MB.brd

R2N12  RES  10.0K 1% EMPTY  pkg 0402  page 133 : A = GND ; B = PWRGD_SYS_PWROK
CT9  CAP  1000PF 50V 10% X7R  pkg 0402LF  page 227 : A = VR_PVDDQ_KLM_PH1_SW ; B = VR_PVDDQ_KLM_PH1_RC
R9B11  RES  0.0 5% CHIP  pkg 0402  page 113 : A = JTAG_MCP_TCK ; B = JTAG_MCP_TCK_R

(kicad_pcb
	(version 20260206)
	(generator "pcbnew")
	(generator_version "10.0")
	(general
		(thickness 1.6)
		(legacy_teardrops no)
	)
	(paper "A4")
	(title_block
		(title "Wiwynn_Tioga_Pass_MB.brd")
		(comment 1 "Tioga Pass / footprints 1174-1176 of 4770")
	)
	(layers
		(0 "F.Cu" signal "TOP")
		(4 "In1.Cu" signal "L2GND")
		(6 "In2.Cu" signal "L3")
		(8 "In3.Cu" signal "L4GND")
		(10 "In4.Cu" signal "L5")
		(12 "In5.Cu" signal "L6GND")
		(14 "In6.Cu" signal "L7VCC")
		(16 "In7.Cu" signal "L8VCC")
		(18 "In8.Cu" signal "L9GND")
		(20 "In9.Cu" signal "L10")
		(22 "In10.Cu" signal "L11GND")
		(24 "In11.Cu" signal "L12")
		(26 "In12.Cu" signal "L13GND")
		(2 "B.Cu" signal "BOTTOM")
		(9 "F.Adhes" user "F.Adhesive")
		(11 "B.Adhes" user "B.Adhesive")
		(13 "F.Paste" user "Package Geometry/Pastemask Top")
		(15 "B.Paste" user "Package Geometry/Pastemask Bottom")
		(5 "F.SilkS" user "Ref Des/Silkscreen Top")
		(7 "B.SilkS" user "Ref Des/Silkscreen Bottom")
		(1 "F.Mask" user "Board Geometry/Soldermask Top")
		(3 "B.Mask" user "Board Geometry/Soldermask Bottom")
		(17 "Dwgs.User" user "User.Drawings")
		(19 "Cmts.User" user "User.Comments")
		(21 "Eco1.User" user "User.Eco1")
		(23 "Eco2.User" user "User.Eco2")
		(25 "Edge.Cuts" user "Board Geometry/Outline")
		(27 "Margin" user)
		(31 "F.CrtYd" user "Package Geometry/Place Bound Top")
		(29 "B.CrtYd" user "Package Geometry/Place Bound Bottom")
		(35 "F.Fab" user "Ref Des/Assembly Top")
		(33 "B.Fab" user "Ref Des/Assembly Bottom")
	)
	(footprint ""
		(layer "F.Cu")
		(at 7.05231 -134.383526 -90)
		(property "Reference" "CT9"
			(at -0.8382 -0.67818 270)
			(unlocked yes)
			(layer "F.SilkS")
			(effects
				(font
					(size 0.4064 0.254)
					(thickness 0.1524)
				)
				(justify left)
			)
		)
		(property "Value" ""
			(at 0 0 270)
			(layer "F.Fab")
			(effects
				(font
					(size 1.27 1.27)
				)
			)
		)
		(duplicate_pad_numbers_are_jumpers no)
		(fp_poly
			(pts
				(xy 0.3048 -0.1016) (xy 0.3048 0.9906) (xy -0.3048 0.9906) (xy -0.3048 -0.1016)
			)
			(stroke
				(width 0)
				(type default)
			)
			(fill no)
			(layer "F.CrtYd")
		)
		(fp_line
			(start -0.3048 0.9906)
			(end 0.3048 0.9906)
			(stroke
				(width 0.1)
				(type default)
			)
			(layer "F.Fab")
		)
		(fp_line
			(start 0.3048 0.9906)
			(end 0.3048 -0.1016)
			(stroke
				(width 0.1)
				(type default)
			)
			(layer "F.Fab")
		)
		(fp_line
			(start -0.3048 -0.1016)
			(end -0.3048 0.9906)
			(stroke
				(width 0.1)
				(type default)
			)
			(layer "F.Fab")
		)
		(fp_line
			(start 0.3048 -0.1016)
			(end -0.3048 -0.1016)
			(stroke
				(width 0.1)
				(type default)
			)
			(layer "F.Fab")
		)
		(pad "1" smd rect
			(at 0 0 270)
			(size 0.508 0.508)
			(layers "F.Cu" "F.Mask" "F.Paste")
			(net "VR_PVDDQ_KLM_PH1_SW")
		)
		(pad "2" smd rect
			(at 0 0.889 270)
			(size 0.508 0.508)
			(layers "F.Cu" "F.Mask" "F.Paste")
			(net "VR_PVDDQ_KLM_PH1_RC")
		)
		(zone
			(layer "F.Cu")
			(hatch none 0.5)
			(connect_pads
				(clearance 0)
			)
			(min_thickness 0.25)
			(keepout
				(tracks not_allowed)
				(vias allowed)
				(pads allowed)
				(copperpour not_allowed)
				(footprints allowed)
			)
			(placement
				(enabled no)
				(sheetname "")
			)
			(fill
				(thermal_gap 0.5)
				(thermal_bridge_width 0.5)
				(island_removal_mode 0)
			)
			(polygon
				(pts
					(xy 6.41731 -134.637526) (xy 6.41731 -134.129526) (xy 6.79831 -134.129526) (xy 6.79831 -134.637526)
				)
			)
		)
		(zone
			(layer "F.Cu")
			(hatch none 0.5)
			(connect_pads
				(clearance 0)
			)
			(min_thickness 0.25)
			(keepout
				(tracks allowed)
				(vias not_allowed)
				(pads allowed)
				(copperpour not_allowed)
				(footprints allowed)
			)
			(placement
				(enabled no)
				(sheetname "")
			)
			(fill
				(thermal_gap 0.5)
				(thermal_bridge_width 0.5)
				(island_removal_mode 0)
			)
			(polygon
				(pts
					(xy 6.79831 -134.637526) (xy 6.79831 -134.129526) (xy 6.41731 -134.129526) (xy 6.41731 -134.637526)
				)
			)
		)
	)
	(footprint ""
		(layer "F.Cu")
		(at 467.36 -134.366 180)
		(property "Reference" "R9B11"
			(at 0 0 180)
			(layer "F.SilkS")
			(hide yes)
			(effects
				(font
					(size 1.27 1.27)
				)
			)
		)
		(property "Value" ""
			(at 0 0 180)
			(layer "F.Fab")
			(effects
				(font
					(size 1.27 1.27)
				)
			)
		)
		(duplicate_pad_numbers_are_jumpers no)
		(fp_poly
			(pts
				(xy -0.2794 -0.1016) (xy 0.2794 -0.1016) (xy 0.2794 0.9906) (xy -0.2794 0.9906)
			)
			(stroke
				(width 0)
				(type default)
			)
			(fill no)
			(layer "F.CrtYd")
		)
		(fp_line
			(start 0.2794 0.9906)
			(end 0.2794 -0.1016)
			(stroke
				(width 0.1)
				(type default)
			)
			(layer "F.Fab")
		)
		(fp_line
			(start 0.2794 -0.1016)
			(end -0.2794 -0.1016)
			(stroke
				(width 0.1)
				(type default)
			)
			(layer "F.Fab")
		)
		(fp_line
			(start -0.2794 0.9906)
			(end 0.2794 0.9906)
			(stroke
				(width 0.1)
				(type default)
			)
			(layer "F.Fab")
		)
		(fp_line
			(start -0.2794 -0.1016)
			(end -0.2794 0.9906)
			(stroke
				(width 0.1)
				(type default)
			)
			(layer "F.Fab")
		)
		(pad "1" smd rect
			(at 0 0 180)
			(size 0.508 0.508)
			(layers "F.Cu" "F.Mask" "F.Paste")
			(net "JTAG_MCP_TCK")
		)
		(pad "2" smd rect
			(at 0 0.889 180)
			(size 0.508 0.508)
			(layers "F.Cu" "F.Mask" "F.Paste")
			(net "JTAG_MCP_TCK_R")
		)
		(zone
			(layer "F.Cu")
			(hatch none 0.5)
			(connect_pads
				(clearance 0)
			)
			(min_thickness 0.25)
			(keepout
				(tracks not_allowed)
				(vias allowed)
				(pads allowed)
				(copperpour not_allowed)
				(footprints allowed)
			)
			(placement
				(enabled no)
				(sheetname "")
			)
			(fill
				(thermal_gap 0.5)
				(thermal_bridge_width 0.5)
				(island_removal_mode 0)
			)
			(polygon
				(pts
					(xy 467.614 -135.001) (xy 467.106 -135.001) (xy 467.106 -134.62) (xy 467.614 -134.62)
				)
			)
		)
		(zone
			(layer "F.Cu")
			(hatch none 0.5)
			(connect_pads
				(clearance 0)
			)
			(min_thickness 0.25)
			(keepout
				(tracks allowed)
				(vias not_allowed)
				(pads allowed)
				(copperpour not_allowed)
				(footprints allowed)
			)
			(placement
				(enabled no)
				(sheetname "")
			)
			(fill
				(thermal_gap 0.5)
				(thermal_bridge_width 0.5)
				(island_removal_mode 0)
			)
			(polygon
				(pts
					(xy 467.614 -134.62) (xy 467.106 -134.62) (xy 467.106 -135.001) (xy 467.614 -135.001)
				)
			)
		)
	)
	(footprint ""
		(layer "F.Cu")
		(at 405.9555 -102.108 -90)
		(property "Reference" "R2N12"
			(at 0 0 270)
			(layer "F.SilkS")
			(hide yes)
			(effects
				(font
					(size 1.27 1.27)
				)
			)
		)
		(property "Value" ""
			(at 0 0 270)
			(layer "F.Fab")
			(effects
				(font
					(size 1.27 1.27)
				)
			)
		)
		(duplicate_pad_numbers_are_jumpers no)
		(fp_poly
			(pts
				(xy -0.2794 -0.1016) (xy 0.2794 -0.1016) (xy 0.2794 0.9906) (xy -0.2794 0.9906)
			)
			(stroke
				(width 0)
				(type default)
			)
			(fill no)
			(layer "F.CrtYd")
		)
		(fp_line
			(start -0.2794 0.9906)
			(end 0.2794 0.9906)
			(stroke
				(width 0.1)
				(type default)
			)
			(layer "F.Fab")
		)
		(fp_line
			(start 0.2794 0.9906)
			(end 0.2794 -0.1016)
			(stroke
				(width 0.1)
				(type default)
			)
			(layer "F.Fab")
		)
		(fp_line
			(start -0.2794 -0.1016)
			(end -0.2794 0.9906)
			(stroke
				(width 0.1)
				(type default)
			)
			(layer "F.Fab")
		)
		(fp_line
			(start 0.2794 -0.1016)
			(end -0.2794 -0.1016)
			(stroke
				(width 0.1)
				(type default)
			)
			(layer "F.Fab")
		)
		(pad "1" smd rect
			(at 0 0 270)
			(size 0.508 0.508)
			(layers "F.Cu" "F.Mask" "F.Paste")
			(net "GND")
		)
		(pad "2" smd rect
			(at 0 0.889 270)
			(size 0.508 0.508)
			(layers "F.Cu" "F.Mask" "F.Paste")
			(net "PWRGD_SYS_PWROK")
		)
		(zone
			(layer "F.Cu")
			(hatch none 0.5)
			(connect_pads
				(clearance 0)
			)
			(min_thickness 0.25)
			(keepout
				(tracks not_allowed)
				(vias allowed)
				(pads allowed)
				(copperpour not_allowed)
				(footprints allowed)
			)
			(placement
				(enabled no)
				(sheetname "")
			)
			(fill
				(thermal_gap 0.5)
				(thermal_bridge_width 0.5)
				(island_removal_mode 0)
			)
			(polygon
				(pts
					(xy 405.3205 -102.362) (xy 405.3205 -101.854) (xy 405.7015 -101.854) (xy 405.7015 -102.362)
				)
			)
		)
		(zone
			(layer "F.Cu")
			(hatch none 0.5)
			(connect_pads
				(clearance 0)
			)
			(min_thickness 0.25)
			(keepout
				(tracks allowed)
				(vias not_allowed)
				(pads allowed)
				(copperpour not_allowed)
				(footprints allowed)
			)
			(placement
				(enabled no)
				(sheetname "")
			)
			(fill
				(thermal_gap 0.5)
				(thermal_bridge_width 0.5)
				(island_removal_mode 0)
			)
			(polygon
				(pts
					(xy 405.7015 -102.362) (xy 405.7015 -101.854) (xy 405.3205 -101.854) (xy 405.3205 -102.362)
				)
			)
		)
	)
)
